# S9S_MB_2U (Grand Teton) — schematic netlist excerpt (pin names and nets, part order shuffled) for the footprints in the layout excerpt that follows; sources: Cadence DE-HDL packaged netlist, KiCad conversion of 03242023_DA0F0TMBIJ0_F0T_Motherboard_J_brd_V01_OCP.brd

R1099  Q_RES  10K 1% CHIP  pkg 0402LF  page 214 : A = P3V3_AUX ; B = PU_CLK25M_OSC_FPGA_EN
R1413  Q_RES  2K 1% CHIP  pkg 0402LF  page 219 : A = FM_PVCCD_HV_CPU0_EN ; B = GND

(kicad_pcb
	(version 20260206)
	(generator "pcbnew")
	(generator_version "10.0")
	(general
		(thickness 1.6)
		(legacy_teardrops no)
	)
	(paper "A4")
	(title_block
		(title "03242023_DA0F0TMBIJ0_F0T_Motherboard_J_brd_V01_OCP.brd")
		(comment 1 "Grand Teton / footprints 2660-2661 of 6105")
	)
	(layers
		(0 "F.Cu" signal "TOP")
		(4 "In1.Cu" signal "GND")
		(6 "In2.Cu" signal "IN1")
		(8 "In3.Cu" signal "GND1")
		(10 "In4.Cu" signal "IN2")
		(12 "In5.Cu" signal "GND2")
		(14 "In6.Cu" signal "IN3")
		(16 "In7.Cu" signal "GND3")
		(18 "In8.Cu" signal "VCC")
		(20 "In9.Cu" signal "VCC1")
		(22 "In10.Cu" signal "GND4")
		(24 "In11.Cu" signal "IN4")
		(26 "In12.Cu" signal "GND5")
		(28 "In13.Cu" signal "IN5")
		(30 "In14.Cu" signal "GND6")
		(32 "In15.Cu" signal "IN6")
		(34 "In16.Cu" signal "GND7")
		(2 "B.Cu" signal "BOTTOM")
		(9 "F.Adhes" user "F.Adhesive")
		(11 "B.Adhes" user "B.Adhesive")
		(13 "F.Paste" user "Package Geometry/Pastemask Top")
		(15 "B.Paste" user "Package Geometry/Pastemask Bottom")
		(5 "F.SilkS" user "Ref Des/Silkscreen Top")
		(7 "B.SilkS" user "Ref Des/Silkscreen Bottom")
		(1 "F.Mask" user "Board Geometry/Soldermask Top")
		(3 "B.Mask" user "Board Geometry/Soldermask Bottom")
		(17 "Dwgs.User" user "User.Drawings")
		(19 "Cmts.User" user "User.Comments")
		(21 "Eco1.User" user "User.Eco1")
		(23 "Eco2.User" user "User.Eco2")
		(25 "Edge.Cuts" user "Board Geometry/Outline")
		(27 "Margin" user)
		(31 "F.CrtYd" user "Package Geometry/Place Bound Top")
		(29 "B.CrtYd" user "Package Geometry/Place Bound Bottom")
		(35 "F.Fab" user "Ref Des/Assembly Top")
		(33 "B.Fab" user "Ref Des/Assembly Bottom")
	)
	(footprint ""
		(layer "F.Cu")
		(at 164.64788 -122.646948 180)
		(property "Reference" "R1413"
			(at 0 0 180)
			(layer "F.SilkS")
			(hide yes)
			(effects
				(font
					(size 1.27 1.27)
				)
			)
		)
		(property "Value" ""
			(at 0 0 180)
			(layer "F.Fab")
			(effects
				(font
					(size 1.27 1.27)
				)
			)
		)
		(duplicate_pad_numbers_are_jumpers no)
		(fp_line
			(start 0.7874 0.4064)
			(end -0.7874 0.4064)
			(stroke
				(width 0.1524)
				(type default)
			)
			(layer "F.SilkS")
		)
		(fp_line
			(start 0.7874 -0.4064)
			(end 0.7874 0.4064)
			(stroke
				(width 0.1524)
				(type default)
			)
			(layer "F.SilkS")
		)
		(fp_line
			(start -0.7874 0.4064)
			(end -0.7874 -0.4064)
			(stroke
				(width 0.1524)
				(type default)
			)
			(layer "F.SilkS")
		)
		(fp_line
			(start -0.7874 -0.4064)
			(end 0.7874 -0.4064)
			(stroke
				(width 0.1524)
				(type default)
			)
			(layer "F.SilkS")
		)
		(fp_line
			(start 0.67945 0.3048)
			(end 0.120396 0.3048)
			(stroke
				(width 0.1)
				(type default)
			)
			(layer "F.Fab")
		)
		(fp_line
			(start 0.67945 -0.3048)
			(end 0.67945 0.3048)
			(stroke
				(width 0.1)
				(type default)
			)
			(layer "F.Fab")
		)
		(fp_line
			(start 0.12065 -0.2794)
			(end 0.12065 -0.3048)
			(stroke
				(width 0.1)
				(type default)
			)
			(layer "F.Fab")
		)
		(fp_line
			(start 0.12065 -0.3048)
			(end 0.67945 -0.3048)
			(stroke
				(width 0.1)
				(type default)
			)
			(layer "F.Fab")
		)
		(fp_line
			(start 0.120396 0.3048)
			(end 0.120396 0.2794)
			(stroke
				(width 0.1)
				(type default)
			)
			(layer "F.Fab")
		)
		(fp_line
			(start 0.120396 0.2794)
			(end -0.12065 0.2794)
			(stroke
				(width 0.1)
				(type default)
			)
			(layer "F.Fab")
		)
		(fp_line
			(start -0.12065 0.3048)
			(end -0.67945 0.3048)
			(stroke
				(width 0.1)
				(type default)
			)
			(layer "F.Fab")
		)
		(fp_line
			(start -0.12065 0.2794)
			(end -0.12065 0.3048)
			(stroke
				(width 0.1)
				(type default)
			)
			(layer "F.Fab")
		)
		(fp_line
			(start -0.12065 -0.2794)
			(end 0.12065 -0.2794)
			(stroke
				(width 0.1)
				(type default)
			)
			(layer "F.Fab")
		)
		(fp_line
			(start -0.12065 -0.305054)
			(end -0.12065 -0.2794)
			(stroke
				(width 0.1)
				(type default)
			)
			(layer "F.Fab")
		)
		(fp_line
			(start -0.67945 0.3048)
			(end -0.67945 -0.305054)
			(stroke
				(width 0.1)
				(type default)
			)
			(layer "F.Fab")
		)
		(fp_line
			(start -0.67945 -0.305054)
			(end -0.12065 -0.305054)
			(stroke
				(width 0.1)
				(type default)
			)
			(layer "F.Fab")
		)
		(pad "1" smd circle
			(at -0.40005 0 180)
			(size 0 0)
			(layers "F.Cu" "F.Mask" "F.Paste")
			(net "FM_PVCCD_HV_CPU0_EN")
		)
		(pad "2" smd circle
			(at 0.40005 0 180)
			(size 0 0)
			(layers "F.Cu" "F.Mask" "F.Paste")
			(net "GND")
		)
	)
	(footprint ""
		(layer "F.Cu")
		(at 197.41388 -113.502948 90)
		(property "Reference" "R1099"
			(at 0 0 90)
			(layer "F.SilkS")
			(hide yes)
			(effects
				(font
					(size 1.27 1.27)
				)
			)
		)
		(property "Value" ""
			(at 0 0 90)
			(layer "F.Fab")
			(effects
				(font
					(size 1.27 1.27)
				)
			)
		)
		(duplicate_pad_numbers_are_jumpers no)
		(fp_line
			(start 0.7874 -0.4064)
			(end 0.7874 0.4064)
			(stroke
				(width 0.1524)
				(type default)
			)
			(layer "F.SilkS")
		)
		(fp_line
			(start -0.7874 -0.4064)
			(end 0.7874 -0.4064)
			(stroke
				(width 0.1524)
				(type default)
			)
			(layer "F.SilkS")
		)
		(fp_line
			(start 0.7874 0.4064)
			(end -0.7874 0.4064)
			(stroke
				(width 0.1524)
				(type default)
			)
			(layer "F.SilkS")
		)
		(fp_line
			(start -0.7874 0.4064)
			(end -0.7874 -0.4064)
			(stroke
				(width 0.1524)
				(type default)
			)
			(layer "F.SilkS")
		)
		(fp_line
			(start -0.12065 -0.305054)
			(end -0.12065 -0.2794)
			(stroke
				(width 0.1)
				(type default)
			)
			(layer "F.Fab")
		)
		(fp_line
			(start -0.67945 -0.305054)
			(end -0.12065 -0.305054)
			(stroke
				(width 0.1)
				(type default)
			)
			(layer "F.Fab")
		)
		(fp_line
			(start 0.67945 -0.3048)
			(end 0.67945 0.3048)
			(stroke
				(width 0.1)
				(type default)
			)
			(layer "F.Fab")
		)
		(fp_line
			(start 0.12065 -0.3048)
			(end 0.67945 -0.3048)
			(stroke
				(width 0.1)
				(type default)
			)
			(layer "F.Fab")
		)
		(fp_line
			(start 0.12065 -0.2794)
			(end 0.12065 -0.3048)
			(stroke
				(width 0.1)
				(type default)
			)
			(layer "F.Fab")
		)
		(fp_line
			(start -0.12065 -0.2794)
			(end 0.12065 -0.2794)
			(stroke
				(width 0.1)
				(type default)
			)
			(layer "F.Fab")
		)
		(fp_line
			(start 0.120396 0.2794)
			(end -0.12065 0.2794)
			(stroke
				(width 0.1)
				(type default)
			)
			(layer "F.Fab")
		)
		(fp_line
			(start -0.12065 0.2794)
			(end -0.12065 0.3048)
			(stroke
				(width 0.1)
				(type default)
			)
			(layer "F.Fab")
		)
		(fp_line
			(start 0.67945 0.3048)
			(end 0.120396 0.3048)
			(stroke
				(width 0.1)
				(type default)
			)
			(layer "F.Fab")
		)
		(fp_line
			(start 0.120396 0.3048)
			(end 0.120396 0.2794)
			(stroke
				(width 0.1)
				(type default)
			)
			(layer "F.Fab")
		)
		(fp_line
			(start -0.12065 0.3048)
			(end -0.67945 0.3048)
			(stroke
				(width 0.1)
				(type default)
			)
			(layer "F.Fab")
		)
		(fp_line
			(start -0.67945 0.3048)
			(end -0.67945 -0.305054)
			(stroke
				(width 0.1)
				(type default)
			)
			(layer "F.Fab")
		)
		(pad "1" smd circle
			(at -0.40005 0 90)
			(size 0 0)
			(layers "F.Cu" "F.Mask" "F.Paste")
			(net "P3V3_AUX")
		)
		(pad "2" smd circle
			(at 0.40005 0 90)
			(size 0 0)
			(layers "F.Cu" "F.Mask" "F.Paste")
			(net "PU_CLK25M_OSC_FPGA_EN")
		)
	)
)
